# SCM (Grand Teton) — schematic netlist excerpt (pin names and nets, part order shuffled) for the footprints in the layout excerpt that follows; sources: Cadence DE-HDL packaged netlist, KiCad conversion of 12092022_DA0F0TMDCD0_F0T_Management_Board_D_brd_V3_OCP.brd

C241  Q_CAP  0.1UF 25V 10% X7R  pkg 0402  page 51 : A = P12V_AUX ; B = GND
D17  Q_DIODE  SDMK0340L-7-F IC  pkg SMLF  page 22 : \1\ = RST_BMC_HW_OUT ; \2\ = RST_BMC_SELF_HW_D

(kicad_pcb
	(version 20260206)
	(generator "pcbnew")
	(generator_version "10.0")
	(general
		(thickness 1.6)
		(legacy_teardrops no)
	)
	(paper "A4")
	(title_block
		(title "12092022_DA0F0TMDCD0_F0T_Management_Board_D_brd_V3_OCP.brd")
		(comment 1 "Grand Teton / footprints 81-82 of 1440")
	)
	(layers
		(0 "F.Cu" signal "TOP")
		(4 "In1.Cu" signal "GND")
		(6 "In2.Cu" signal "IN1")
		(8 "In3.Cu" signal "GND1")
		(10 "In4.Cu" signal "IN2")
		(12 "In5.Cu" signal "VCC")
		(14 "In6.Cu" signal "VCC1")
		(16 "In7.Cu" signal "IN3")
		(18 "In8.Cu" signal "GND2")
		(20 "In9.Cu" signal "IN4")
		(22 "In10.Cu" signal "GND3")
		(2 "B.Cu" signal "BOTTOM")
		(9 "F.Adhes" user "F.Adhesive")
		(11 "B.Adhes" user "B.Adhesive")
		(13 "F.Paste" user "Package Geometry/Pastemask Top")
		(15 "B.Paste" user "Package Geometry/Pastemask Bottom")
		(5 "F.SilkS" user "Ref Des/Silkscreen Top")
		(7 "B.SilkS" user "Ref Des/Silkscreen Bottom")
		(1 "F.Mask" user "Board Geometry/Soldermask Top")
		(3 "B.Mask" user "Board Geometry/Soldermask Bottom")
		(17 "Dwgs.User" user "User.Drawings")
		(19 "Cmts.User" user "User.Comments")
		(21 "Eco1.User" user "User.Eco1")
		(23 "Eco2.User" user "User.Eco2")
		(25 "Edge.Cuts" user "Board Geometry/Outline")
		(27 "Margin" user)
		(31 "F.CrtYd" user "Package Geometry/Place Bound Top")
		(29 "B.CrtYd" user "Package Geometry/Place Bound Bottom")
		(35 "F.Fab" user "Ref Des/Assembly Top")
		(33 "B.Fab" user "Ref Des/Assembly Bottom")
	)
	(footprint ""
		(layer "F.Cu")
		(at 4.572 -58.8264 90)
		(property "Reference" "C241"
			(at 0 0 90)
			(layer "F.SilkS")
			(hide yes)
			(effects
				(font
					(size 1.27 1.27)
				)
			)
		)
		(property "Value" ""
			(at 0 0 90)
			(layer "F.Fab")
			(effects
				(font
					(size 1.27 1.27)
				)
			)
		)
		(duplicate_pad_numbers_are_jumpers no)
		(fp_line
			(start 0.7874 -0.4064)
			(end 0.7874 0.4064)
			(stroke
				(width 0.1524)
				(type default)
			)
			(layer "F.SilkS")
		)
		(fp_line
			(start -0.7874 -0.4064)
			(end 0.7874 -0.4064)
			(stroke
				(width 0.1524)
				(type default)
			)
			(layer "F.SilkS")
		)
		(fp_line
			(start 0.7874 0.4064)
			(end -0.7874 0.4064)
			(stroke
				(width 0.1524)
				(type default)
			)
			(layer "F.SilkS")
		)
		(fp_line
			(start -0.7874 0.4064)
			(end -0.7874 -0.4064)
			(stroke
				(width 0.1524)
				(type default)
			)
			(layer "F.SilkS")
		)
		(fp_line
			(start -0.12065 -0.305054)
			(end -0.12065 -0.2794)
			(stroke
				(width 0.1)
				(type default)
			)
			(layer "F.Fab")
		)
		(fp_line
			(start -0.67945 -0.305054)
			(end -0.12065 -0.305054)
			(stroke
				(width 0.1)
				(type default)
			)
			(layer "F.Fab")
		)
		(fp_line
			(start 0.67945 -0.3048)
			(end 0.67945 0.3048)
			(stroke
				(width 0.1)
				(type default)
			)
			(layer "F.Fab")
		)
		(fp_line
			(start 0.12065 -0.3048)
			(end 0.67945 -0.3048)
			(stroke
				(width 0.1)
				(type default)
			)
			(layer "F.Fab")
		)
		(fp_line
			(start 0.12065 -0.2794)
			(end 0.12065 -0.3048)
			(stroke
				(width 0.1)
				(type default)
			)
			(layer "F.Fab")
		)
		(fp_line
			(start -0.12065 -0.2794)
			(end 0.12065 -0.2794)
			(stroke
				(width 0.1)
				(type default)
			)
			(layer "F.Fab")
		)
		(fp_line
			(start 0.120396 0.2794)
			(end -0.12065 0.2794)
			(stroke
				(width 0.1)
				(type default)
			)
			(layer "F.Fab")
		)
		(fp_line
			(start -0.12065 0.2794)
			(end -0.12065 0.3048)
			(stroke
				(width 0.1)
				(type default)
			)
			(layer "F.Fab")
		)
		(fp_line
			(start 0.67945 0.3048)
			(end 0.120396 0.3048)
			(stroke
				(width 0.1)
				(type default)
			)
			(layer "F.Fab")
		)
		(fp_line
			(start 0.120396 0.3048)
			(end 0.120396 0.2794)
			(stroke
				(width 0.1)
				(type default)
			)
			(layer "F.Fab")
		)
		(fp_line
			(start -0.12065 0.3048)
			(end -0.67945 0.3048)
			(stroke
				(width 0.1)
				(type default)
			)
			(layer "F.Fab")
		)
		(fp_line
			(start -0.67945 0.3048)
			(end -0.67945 -0.305054)
			(stroke
				(width 0.1)
				(type default)
			)
			(layer "F.Fab")
		)
		(pad "1" smd circle
			(at -0.40005 0 90)
			(size 0 0)
			(layers "F.Cu" "F.Mask" "F.Paste")
			(net "P12V_AUX")
		)
		(pad "2" smd circle
			(at 0.40005 0 90)
			(size 0 0)
			(layers "F.Cu" "F.Mask" "F.Paste")
			(net "GND")
		)
	)
	(footprint ""
		(layer "F.Cu")
		(at 26.3398 -105.4608 180)
		(property "Reference" "D17"
			(at 2.3368 1.44653 0)
			(unlocked yes)
			(layer "F.SilkS")
			(effects
				(font
					(size 0.7874 0.5842)
					(thickness 0.1524)
				)
				(justify left)
			)
		)
		(property "Value" ""
			(at 0 0 180)
			(layer "F.Fab")
			(effects
				(font
					(size 1.27 1.27)
				)
			)
		)
		(duplicate_pad_numbers_are_jumpers no)
		(fp_line
			(start 2.343404 0.6985)
			(end 2.216404 0.6985)
			(stroke
				(width 0.1524)
				(type default)
			)
			(layer "F.SilkS")
		)
		(fp_line
			(start 2.343404 -0.6985)
			(end 2.343404 0.6985)
			(stroke
				(width 0.1524)
				(type default)
			)
			(layer "F.SilkS")
		)
		(fp_line
			(start 2.229104 0.6985)
			(end 2.051304 0.6985)
			(stroke
				(width 0.1524)
				(type default)
			)
			(layer "F.SilkS")
		)
		(fp_line
			(start 2.229104 -0.6985)
			(end 2.229104 0.6985)
			(stroke
				(width 0.1524)
				(type default)
			)
			(layer "F.SilkS")
		)
		(fp_line
			(start 2.152904 0.635)
			(end 2.152904 -0.6985)
			(stroke
				(width 0.1524)
				(type default)
			)
			(layer "F.SilkS")
		)
		(fp_line
			(start 2.152904 -0.6985)
			(end 2.343404 -0.6985)
			(stroke
				(width 0.1524)
				(type default)
			)
			(layer "F.SilkS")
		)
		(fp_line
			(start 2.064004 -0.6731)
			(end 2.064004 -0.6985)
			(stroke
				(width 0.1524)
				(type default)
			)
			(layer "F.SilkS")
		)
		(fp_line
			(start 2.064004 -0.6985)
			(end 2.229104 -0.6985)
			(stroke
				(width 0.1524)
				(type default)
			)
			(layer "F.SilkS")
		)
		(fp_line
			(start 2.051304 0.6985)
			(end 2.051304 0.635)
			(stroke
				(width 0.1524)
				(type default)
			)
			(layer "F.SilkS")
		)
		(fp_line
			(start 2.051304 0.635)
			(end 2.152904 0.635)
			(stroke
				(width 0.1524)
				(type default)
			)
			(layer "F.SilkS")
		)
		(fp_line
			(start 2.050796 0.700024)
			(end -2.050796 0.700024)
			(stroke
				(width 0.1524)
				(type default)
			)
			(layer "F.SilkS")
		)
		(fp_line
			(start 2.050796 -0.700024)
			(end 2.050796 0.700024)
			(stroke
				(width 0.1524)
				(type default)
			)
			(layer "F.SilkS")
		)
		(fp_line
			(start 0.293878 -0.500126)
			(end 0.293878 0.500126)
			(stroke
				(width 0.1524)
				(type default)
			)
			(layer "F.SilkS")
		)
		(fp_line
			(start 0.193802 0)
			(end -0.30607 -0.500126)
			(stroke
				(width 0.1524)
				(type default)
			)
			(layer "F.SilkS")
		)
		(fp_line
			(start -0.30607 0.500126)
			(end 0.193802 0)
			(stroke
				(width 0.1524)
				(type default)
			)
			(layer "F.SilkS")
		)
		(fp_line
			(start -0.30607 -0.500126)
			(end -0.30607 0.500126)
			(stroke
				(width 0.1524)
				(type default)
			)
			(layer "F.SilkS")
		)
		(fp_line
			(start -2.050796 0.700024)
			(end -2.050796 -0.700024)
			(stroke
				(width 0.1524)
				(type default)
			)
			(layer "F.SilkS")
		)
		(fp_line
			(start -2.050796 -0.700024)
			(end 2.050796 -0.700024)
			(stroke
				(width 0.1524)
				(type default)
			)
			(layer "F.SilkS")
		)
		(fp_line
			(start 0.899922 0.700024)
			(end -0.899922 0.700024)
			(stroke
				(width 0.1)
				(type default)
			)
			(layer "F.Fab")
		)
		(fp_line
			(start 0.899922 -0.700024)
			(end 0.899922 0.700024)
			(stroke
				(width 0.1)
				(type default)
			)
			(layer "F.Fab")
		)
		(fp_line
			(start -0.899922 0.700024)
			(end -0.899922 -0.700024)
			(stroke
				(width 0.1)
				(type default)
			)
			(layer "F.Fab")
		)
		(fp_line
			(start -0.899922 -0.700024)
			(end 0.899922 -0.700024)
			(stroke
				(width 0.1)
				(type default)
			)
			(layer "F.Fab")
		)
		(fp_text user "-"
			(at 2.1082 -0.92075 0)
			(unlocked yes)
			(layer "F.SilkS")
			(effects
				(font
					(size 1.905 1.4224)
					(thickness 0.1524)
				)
				(justify left)
			)
		)
		(fp_text user "+"
			(at -1.94945 -0.5588 270)
			(unlocked yes)
			(layer "F.SilkS")
			(effects
				(font
					(size 1.905 1.4224)
					(thickness 0.1524)
				)
				(justify left)
			)
		)
		(fp_text user "-"
			(at 3.880104 0.23495 0)
			(unlocked yes)
			(layer "F.Fab")
			(effects
				(font
					(size 1.905 1.4224)
					(thickness 0.1524)
				)
				(justify left)
			)
		)
		(fp_text user "+"
			(at -3.123946 0.762 270)
			(unlocked yes)
			(layer "F.Fab")
			(effects
				(font
					(size 1.905 1.4224)
					(thickness 0.1524)
				)
				(justify left)
			)
		)
		(pad "1" smd rect
			(at -1.199896 0 90)
			(size 0.6604 1.3716)
			(layers "F.Cu" "F.Mask" "F.Paste")
			(net "RST_BMC_HW_OUT")
		)
		(pad "2" smd rect
			(at 1.199896 0 270)
			(size 0.6604 1.3716)
			(layers "F.Cu" "F.Mask" "F.Paste")
			(net "RST_BMC_SELF_HW_D")
		)
	)
)
